FILE_TYPE = MULTI_PHYS_TABLE;

PART 'MOSFET_DUAL_6P'

{========================================================================================}
:VALUE          | PART_TYPE | MATERIAL | PART_NUMBER       = STANDARD        | LIFECYCLE      | PART_NUMBER       | JEDEC_TYPE     | DESCRIPTION                                | MANUFTR | MANUF_PN       | RD_CMPLS_LVL | CMPLS_LVL | CLASS | DIP_SMD | FP_ECN           | FROM_PJ        | DATA                   | EE_CHECK_LIST | STATUS | PSL | PREFERENCE | CREATOR | CREATEDAY  ;
{========================================================================================}
 'DMN2400UV-7'  | 'SMLF'    | 'IC'     | 'BAM24000000'(!)  = ''              | ''             | 'BAM24000000'     |'SOT563-6XA'| 'TRANS MOS DMN2400UV-7(20V,1.33A,0.53W)'   | 'DDS'   | 'DMN2400UV-7'  | 'EP(V1)'     | 'EP(V1)'  | 'IC'  | ''      | ''               | 'S1N-AI-JU'    | 'DDS_DMN2400UV.pdf'    | ''            | ''     | ''  | ''         | ''      | '20120626'
 'DMN2400UV-7'  | 'SMLF'    | 'EMPTY'  | 'BAM24000000'(!)  = ''              | ''             | 'BAM24000000'     |'SOT563-6XA'| 'TRANS MOS DMN2400UV-7(20V,1.33A,0.53W)'   | 'DDS'   | 'DMN2400UV-7'  | 'EP(V1)'     | 'EP(V1)'  | 'IC'  | ''      | ''               | 'S1N-AI-JU'    | 'DDS_DMN2400UV.pdf'    | ''            | ''     | ''  | ''         | ''      | '20120626'
 'NX7002AKS'    | 'SMLF'    | 'IC'     | 'BAM70020069'(!)  = 'End of Design' | 'Comp-Approve' | 'BAM70020069'     |'SOT363XB'| 'TRANS MOSFET NX7002AKS(60V,170MA,1.06W)'  | 'NXP'   | 'NX7002AKS'    | 'EP(V1)'     | ''        | 'IC'  | ''      | ''               | 'S1N-AI-JU'    | 'NXP_NX7002AKS.pdf'    | ''            | ''     | ''  | ''         | ''      | '20120626'
 'NX7002AKS'    | 'SMLF'    | 'EMPTY'  | 'BAM70020069'(!)  = 'End of Design' | 'Comp-Approve' | 'BAM70020069'     |'SOT363XB'| 'TRANS MOSFET NX7002AKS(60V,170MA,1.06W)'  | 'NXP'   | 'NX7002AKS'    | 'EP(V1)'     | ''        | 'IC'  | ''      | ''               | 'S1N-AI-JU'    | 'NXP_NX7002AKS.pdf'    | ''            | ''     | ''  | ''         | ''      | '20120626'
 '2N7002KDW'    | 'SMLF'    | 'IC'     | 'BAM70020047'(!)  = ''              | ''             | 'BAM70020047'     |'SOT363XD'| 'TRANS MOS 2N7002KDW(60V115MA,0.2W)SOT363' | 'PJT'   | '2N7002KDW'    | 'EP(V1)'     | 'EP(V1)'  | 'IC'  | ''      | ''               | 'F06S-KENG-YU' | 'PJT_2N7002KDW.pdf'    | ''            | ''     | ''  | ''         | ''      | '20140113'
 '2N7002KDW'    | 'SMLF'    | 'EMPTY'  | 'BAM70020047'(!)  = ''              | ''             | 'BAM70020047'     |'SOT363XD'| 'TRANS MOS 2N7002KDW(60V115MA,0.2W)SOT363' | 'PJT'   | '2N7002KDW'    | 'EP(V1)'     | 'EP(V1)'  | 'IC'  | ''      | ''               | 'F06S-KENG-YU' | 'PJT_2N7002KDW.pdf'    | ''            | ''     | ''  | ''         | ''      | '20140113'
 '2N7002DWKX-7' | 'SMLF'    | 'IC'     | 'BAM70020079'(!)  = 'Potential'     | 'End of Life'  | 'BAM70020079'     |'SOT363XA_EOL'| 'TR MOS 2N7002DWKX-7(60V115MA,0.2W)SOT363' | 'DDS'   | '2N7002DWKX-7' | 'EP(V1)'     | 'EP(V1)'  | 'IC'  | ''      | ''               | 'S4LZ-ROGER'   | 'DDS_2N7002DWKX-7.pdf' | ''            | ''     | ''  | ''         | ''      | '20140502'
 '2N7002DWKX-7' | 'SMLF'    | 'EMPTY'  | 'BAM70020079'(!)  = 'Potential'     | 'End of Life'  | 'BAM70020079'     |'SOT363XA_EOL'| 'TR MOS 2N7002DWKX-7(60V115MA,0.2W)SOT363' | 'DDS'   | '2N7002DWKX-7' | 'EP(V1)'     | 'EP(V1)'  | 'IC'  | ''      | ''               | 'S4LZ-ROGER'   | 'DDS_2N7002DWKX-7.pdf' | ''            | ''     | ''  | ''         | ''      | '20140502'
 'NX3020NAKV'   | 'SMLF'    | 'IC'     | 'BAM30200003'(!)  = ''              | ''             | 'BAM30200003'     |'SOT666'| 'TRANS MOSFET NX3020NAKV(30V,200MA,0.26W)' | 'NXP'   | 'NX3020NAKV'   | 'EU(V1)'     | 'EU(V1)'  | 'IC'  | ''      | ''               | 'S3D-ALAN'     | 'NXP_NX3020NAKV.pdf'   | ''            | ''     | ''  | ''         | ''      | '20191220'
 'NX3020NAKV'   | 'SMLF'    | 'EMPTY'  | 'BAM30200003'(!)  = ''              | ''             | 'BAM30200003'     |'SOT666'| 'TRANS MOSFET NX3020NAKV(30V,200MA,0.26W)' | 'NXP'   | 'NX3020NAKV'   | 'EU(V1)'     | 'EU(V1)'  | 'IC'  | ''      | ''               | 'S3D-ALAN'     | 'NXP_NX3020NAKV.pdf'   | ''            | ''     | ''  | ''         | ''      | '20191220'
 '2N7002KDW'    | 'SMLF'    | 'IC'     | 'BAM70020047SEL1'(!) = ''              | ''               | 'BAM70020047SEL1' |'SOT363XD'| 'TRANS MOS 2N7002(60V115MA0.2W)SOT363SELA' | 'PJT'   | '2N7002KDW'    | 'EP(V1)'     | 'EP(V1)'  | 'IC'  | ''      | 'SEL_15QPN.xlsx' | 'F06S-KENG-YU' | 'PJT_2N7002KDW.pdf'    | ''            | ''     | ''  | ''         | ''      | '20230626'
 '2N7002KDW'    | 'SMLF'    | 'EMPTY'  | 'BAM70020047SEL1'(!) = ''              | ''               | 'BAM70020047SEL1' |'SOT363XD'| 'TRANS MOS 2N7002(60V115MA0.2W)SOT363SELA' | 'PJT'   | '2N7002KDW'    | 'EP(V1)'     | 'EP(V1)'  | 'IC'  | ''      | 'SEL_15QPN.xlsx' | 'F06S-KENG-YU' | 'PJT_2N7002KDW.pdf'    | ''            | ''     | ''  | ''         | ''      | '20230626'

END_PART

END.

